# S9S_MB_2U (Grand Teton) — schematic netlist excerpt (pin names and nets, part order shuffled) for the footprints in the layout excerpt that follows; sources: Cadence DE-HDL packaged netlist, KiCad conversion of 03242023_DA0F0TMBIJ0_F0T_Motherboard_J_brd_V01_OCP.brd

R3066  Q_RES  0 5% CHIP  pkg 0402LF  page 214 : A = FM_SMB_1_ALERT_GPU_ISO_N ; B = FM_SMB_1_ALERT_GPU_ISO_R_N
R4145  Q_RES  33.2 1% CHIP  pkg 0402LF  page 215 : A = PRSNT_CABLE_GPU_B3_ISO_N ; B = PRSNT_CABLE_GPU_B3_ISO_R_N
C695  Q_CAP_DIFFBUS  DIFF BUS_0.22UF 6.3V 20% X6S  pkg C0201  page 177 : \1\ = P5E_CPU1_PE4_TX_C_DP<7> ; \2\ = P5E_CPU1_PE4_TX_DP<7>

(kicad_pcb
	(version 20260206)
	(generator "pcbnew")
	(generator_version "10.0")
	(general
		(thickness 1.6)
		(legacy_teardrops no)
	)
	(paper "A4")
	(title_block
		(title "03242023_DA0F0TMBIJ0_F0T_Motherboard_J_brd_V01_OCP.brd")
		(comment 1 "Grand Teton / footprints 162-164 of 6105")
	)
	(layers
		(0 "F.Cu" signal "TOP")
		(4 "In1.Cu" signal "GND")
		(6 "In2.Cu" signal "IN1")
		(8 "In3.Cu" signal "GND1")
		(10 "In4.Cu" signal "IN2")
		(12 "In5.Cu" signal "GND2")
		(14 "In6.Cu" signal "IN3")
		(16 "In7.Cu" signal "GND3")
		(18 "In8.Cu" signal "VCC")
		(20 "In9.Cu" signal "VCC1")
		(22 "In10.Cu" signal "GND4")
		(24 "In11.Cu" signal "IN4")
		(26 "In12.Cu" signal "GND5")
		(28 "In13.Cu" signal "IN5")
		(30 "In14.Cu" signal "GND6")
		(32 "In15.Cu" signal "IN6")
		(34 "In16.Cu" signal "GND7")
		(2 "B.Cu" signal "BOTTOM")
		(9 "F.Adhes" user "F.Adhesive")
		(11 "B.Adhes" user "B.Adhesive")
		(13 "F.Paste" user "Package Geometry/Pastemask Top")
		(15 "B.Paste" user "Package Geometry/Pastemask Bottom")
		(5 "F.SilkS" user "Ref Des/Silkscreen Top")
		(7 "B.SilkS" user "Ref Des/Silkscreen Bottom")
		(1 "F.Mask" user "Board Geometry/Soldermask Top")
		(3 "B.Mask" user "Board Geometry/Soldermask Bottom")
		(17 "Dwgs.User" user "User.Drawings")
		(19 "Cmts.User" user "User.Comments")
		(21 "Eco1.User" user "User.Eco1")
		(23 "Eco2.User" user "User.Eco2")
		(25 "Edge.Cuts" user "Board Geometry/Outline")
		(27 "Margin" user)
		(31 "F.CrtYd" user "Package Geometry/Place Bound Top")
		(29 "B.CrtYd" user "Package Geometry/Place Bound Bottom")
		(35 "F.Fab" user "Ref Des/Assembly Top")
		(33 "B.Fab" user "Ref Des/Assembly Bottom")
	)
	(footprint ""
		(layer "F.Cu")
		(at 22.935438 -423.64152 -90)
		(property "Reference" "R3066"
			(at 0 0 270)
			(layer "F.SilkS")
			(hide yes)
			(effects
				(font
					(size 1.27 1.27)
				)
			)
		)
		(property "Value" ""
			(at 0 0 270)
			(layer "F.Fab")
			(effects
				(font
					(size 1.27 1.27)
				)
			)
		)
		(duplicate_pad_numbers_are_jumpers no)
		(fp_line
			(start -0.7874 0.4064)
			(end -0.7874 -0.4064)
			(stroke
				(width 0.1524)
				(type default)
			)
			(layer "F.SilkS")
		)
		(fp_line
			(start 0.7874 0.4064)
			(end -0.7874 0.4064)
			(stroke
				(width 0.1524)
				(type default)
			)
			(layer "F.SilkS")
		)
		(fp_line
			(start -0.7874 -0.4064)
			(end 0.7874 -0.4064)
			(stroke
				(width 0.1524)
				(type default)
			)
			(layer "F.SilkS")
		)
		(fp_line
			(start 0.7874 -0.4064)
			(end 0.7874 0.4064)
			(stroke
				(width 0.1524)
				(type default)
			)
			(layer "F.SilkS")
		)
		(fp_line
			(start -0.67945 0.3048)
			(end -0.67945 -0.305054)
			(stroke
				(width 0.1)
				(type default)
			)
			(layer "F.Fab")
		)
		(fp_line
			(start -0.12065 0.3048)
			(end -0.67945 0.3048)
			(stroke
				(width 0.1)
				(type default)
			)
			(layer "F.Fab")
		)
		(fp_line
			(start 0.120396 0.3048)
			(end 0.120396 0.2794)
			(stroke
				(width 0.1)
				(type default)
			)
			(layer "F.Fab")
		)
		(fp_line
			(start 0.67945 0.3048)
			(end 0.120396 0.3048)
			(stroke
				(width 0.1)
				(type default)
			)
			(layer "F.Fab")
		)
		(fp_line
			(start -0.12065 0.2794)
			(end -0.12065 0.3048)
			(stroke
				(width 0.1)
				(type default)
			)
			(layer "F.Fab")
		)
		(fp_line
			(start 0.120396 0.2794)
			(end -0.12065 0.2794)
			(stroke
				(width 0.1)
				(type default)
			)
			(layer "F.Fab")
		)
		(fp_line
			(start -0.12065 -0.2794)
			(end 0.12065 -0.2794)
			(stroke
				(width 0.1)
				(type default)
			)
			(layer "F.Fab")
		)
		(fp_line
			(start 0.12065 -0.2794)
			(end 0.12065 -0.3048)
			(stroke
				(width 0.1)
				(type default)
			)
			(layer "F.Fab")
		)
		(fp_line
			(start 0.12065 -0.3048)
			(end 0.67945 -0.3048)
			(stroke
				(width 0.1)
				(type default)
			)
			(layer "F.Fab")
		)
		(fp_line
			(start 0.67945 -0.3048)
			(end 0.67945 0.3048)
			(stroke
				(width 0.1)
				(type default)
			)
			(layer "F.Fab")
		)
		(fp_line
			(start -0.67945 -0.305054)
			(end -0.12065 -0.305054)
			(stroke
				(width 0.1)
				(type default)
			)
			(layer "F.Fab")
		)
		(fp_line
			(start -0.12065 -0.305054)
			(end -0.12065 -0.2794)
			(stroke
				(width 0.1)
				(type default)
			)
			(layer "F.Fab")
		)
		(pad "1" smd circle
			(at -0.40005 0 270)
			(size 0 0)
			(layers "F.Cu" "F.Mask" "F.Paste")
			(net "FM_SMB_1_ALERT_GPU_ISO_N")
		)
		(pad "2" smd circle
			(at 0.40005 0 270)
			(size 0 0)
			(layers "F.Cu" "F.Mask" "F.Paste")
			(net "FM_SMB_1_ALERT_GPU_ISO_R_N")
		)
	)
	(footprint ""
		(layer "F.Cu")
		(at 71.657718 -408.517344 -90)
		(property "Reference" "C695"
			(at 0 0 270)
			(layer "F.SilkS")
			(hide yes)
			(effects
				(font
					(size 1.27 1.27)
				)
			)
		)
		(property "Value" ""
			(at 0 0 270)
			(layer "F.Fab")
			(effects
				(font
					(size 1.27 1.27)
				)
			)
		)
		(duplicate_pad_numbers_are_jumpers no)
		(fp_line
			(start -0.299974 0.150114)
			(end -0.299974 -0.150114)
			(stroke
				(width 0.1)
				(type default)
			)
			(layer "F.Fab")
		)
		(fp_line
			(start 0.299974 0.150114)
			(end -0.299974 0.150114)
			(stroke
				(width 0.1)
				(type default)
			)
			(layer "F.Fab")
		)
		(fp_line
			(start -0.299974 -0.150114)
			(end 0.299974 -0.150114)
			(stroke
				(width 0.1)
				(type default)
			)
			(layer "F.Fab")
		)
		(fp_line
			(start 0.299974 -0.150114)
			(end 0.299974 0.150114)
			(stroke
				(width 0.1)
				(type default)
			)
			(layer "F.Fab")
		)
		(pad "1" smd rect
			(at -0.2667 0 270)
			(size 0.3048 0.381)
			(layers "F.Cu" "F.Mask" "F.Paste")
			(net "P5E_CPU1_PE4_TX_C_DP<7>")
		)
		(pad "2" smd rect
			(at 0.2667 0 270)
			(size 0.3048 0.381)
			(layers "F.Cu" "F.Mask" "F.Paste")
			(net "P5E_CPU1_PE4_TX_DP<7>")
		)
	)
	(footprint ""
		(layer "F.Cu")
		(at 201.00036 -112.994948 180)
		(property "Reference" "R4145"
			(at 0 0 180)
			(layer "F.SilkS")
			(hide yes)
			(effects
				(font
					(size 1.27 1.27)
				)
			)
		)
		(property "Value" ""
			(at 0 0 180)
			(layer "F.Fab")
			(effects
				(font
					(size 1.27 1.27)
				)
			)
		)
		(duplicate_pad_numbers_are_jumpers no)
		(fp_line
			(start 0.7874 0.4064)
			(end -0.7874 0.4064)
			(stroke
				(width 0.1524)
				(type default)
			)
			(layer "F.SilkS")
		)
		(fp_line
			(start 0.7874 -0.4064)
			(end 0.7874 0.4064)
			(stroke
				(width 0.1524)
				(type default)
			)
			(layer "F.SilkS")
		)
		(fp_line
			(start -0.7874 0.4064)
			(end -0.7874 -0.4064)
			(stroke
				(width 0.1524)
				(type default)
			)
			(layer "F.SilkS")
		)
		(fp_line
			(start -0.7874 -0.4064)
			(end 0.7874 -0.4064)
			(stroke
				(width 0.1524)
				(type default)
			)
			(layer "F.SilkS")
		)
		(fp_line
			(start 0.67945 0.3048)
			(end 0.120396 0.3048)
			(stroke
				(width 0.1)
				(type default)
			)
			(layer "F.Fab")
		)
		(fp_line
			(start 0.67945 -0.3048)
			(end 0.67945 0.3048)
			(stroke
				(width 0.1)
				(type default)
			)
			(layer "F.Fab")
		)
		(fp_line
			(start 0.12065 -0.2794)
			(end 0.12065 -0.3048)
			(stroke
				(width 0.1)
				(type default)
			)
			(layer "F.Fab")
		)
		(fp_line
			(start 0.12065 -0.3048)
			(end 0.67945 -0.3048)
			(stroke
				(width 0.1)
				(type default)
			)
			(layer "F.Fab")
		)
		(fp_line
			(start 0.120396 0.3048)
			(end 0.120396 0.2794)
			(stroke
				(width 0.1)
				(type default)
			)
			(layer "F.Fab")
		)
		(fp_line
			(start 0.120396 0.2794)
			(end -0.12065 0.2794)
			(stroke
				(width 0.1)
				(type default)
			)
			(layer "F.Fab")
		)
		(fp_line
			(start -0.12065 0.3048)
			(end -0.67945 0.3048)
			(stroke
				(width 0.1)
				(type default)
			)
			(layer "F.Fab")
		)
		(fp_line
			(start -0.12065 0.2794)
			(end -0.12065 0.3048)
			(stroke
				(width 0.1)
				(type default)
			)
			(layer "F.Fab")
		)
		(fp_line
			(start -0.12065 -0.2794)
			(end 0.12065 -0.2794)
			(stroke
				(width 0.1)
				(type default)
			)
			(layer "F.Fab")
		)
		(fp_line
			(start -0.12065 -0.305054)
			(end -0.12065 -0.2794)
			(stroke
				(width 0.1)
				(type default)
			)
			(layer "F.Fab")
		)
		(fp_line
			(start -0.67945 0.3048)
			(end -0.67945 -0.305054)
			(stroke
				(width 0.1)
				(type default)
			)
			(layer "F.Fab")
		)
		(fp_line
			(start -0.67945 -0.305054)
			(end -0.12065 -0.305054)
			(stroke
				(width 0.1)
				(type default)
			)
			(layer "F.Fab")
		)
		(pad "1" smd circle
			(at -0.40005 0 180)
			(size 0 0)
			(layers "F.Cu" "F.Mask" "F.Paste")
			(net "PRSNT_CABLE_GPU_B3_ISO_N")
		)
		(pad "2" smd circle
			(at 0.40005 0 180)
			(size 0 0)
			(layers "F.Cu" "F.Mask" "F.Paste")
			(net "PRSNT_CABLE_GPU_B3_ISO_R_N")
		)
	)
)
